(kicad_pcb
	(version 20260206)
	(generator "pcbnew")
	(generator_version "10.0")
	(general
		(thickness 1.6)
		(legacy_teardrops no)
	)
	(paper "A4")
	(title_block
		(title "01162023_DA0F0TEBIF0_F0T_Expander_BD_F_brd_V02_OCP.brd")
		(comment 1 "Grand Teton / footprints 9266-9274 of 9728")
	)
	(layers
		(0 "F.Cu" signal "TOP")
		(4 "In1.Cu" signal "GND")
		(6 "In2.Cu" signal "VCC")
		(8 "In3.Cu" signal "VCC1")
		(10 "In4.Cu" signal "GND1")
		(12 "In5.Cu" signal "IN1")
		(14 "In6.Cu" signal "GND2")
		(16 "In7.Cu" signal "IN2")
		(18 "In8.Cu" signal "GND3")
		(20 "In9.Cu" signal "IN3")
		(22 "In10.Cu" signal "GND4")
		(24 "In11.Cu" signal "IN4")
		(26 "In12.Cu" signal "GND5")
		(28 "In13.Cu" signal "IN5")
		(30 "In14.Cu" signal "GND6")
		(32 "In15.Cu" signal "IN6")
		(34 "In16.Cu" signal "GND7")
		(2 "B.Cu" signal "BOTTOM")
		(9 "F.Adhes" user "F.Adhesive")
		(11 "B.Adhes" user "B.Adhesive")
		(13 "F.Paste" user "Package Geometry/Pastemask Top")
		(15 "B.Paste" user "Package Geometry/Pastemask Bottom")
		(5 "F.SilkS" user "Ref Des/Silkscreen Top")
		(7 "B.SilkS" user "Ref Des/Silkscreen Bottom")
		(1 "F.Mask" user "Board Geometry/Soldermask Top")
		(3 "B.Mask" user "Board Geometry/Soldermask Bottom")
		(17 "Dwgs.User" user "User.Drawings")
		(19 "Cmts.User" user "User.Comments")
		(21 "Eco1.User" user "User.Eco1")
		(23 "Eco2.User" user "User.Eco2")
		(25 "Edge.Cuts" user "Board Geometry/Outline")
		(27 "Margin" user)
		(31 "F.CrtYd" user "Package Geometry/Place Bound Top")
		(29 "B.CrtYd" user "Package Geometry/Place Bound Bottom")
		(35 "F.Fab" user "Ref Des/Assembly Top")
		(33 "B.Fab" user "Ref Des/Assembly Bottom")
	)
	(footprint ""
		(layer "B.Cu")
		(at 103.199184 -308.62397 90)
		(property "Reference" "C4200"
			(at 0 0 90)
			(layer "B.SilkS")
			(hide yes)
			(effects
				(font
					(size 1.27 1.27)
				)
				(justify mirror)
			)
		)
		(property "Value" ""
			(at 0 0 90)
			(layer "B.Fab")
			(effects
				(font
					(size 1.27 1.27)
				)
				(justify mirror)
			)
		)
		(duplicate_pad_numbers_are_jumpers no)
		(fp_line
			(start 0.299974 -0.150114)
			(end -0.299974 -0.150114)
			(stroke
				(width 0.1)
				(type default)
			)
			(layer "B.Fab")
		)
		(fp_line
			(start -0.299974 -0.150114)
			(end -0.299974 0.150114)
			(stroke
				(width 0.1)
				(type default)
			)
			(layer "B.Fab")
		)
		(fp_line
			(start 0.299974 0.150114)
			(end 0.299974 -0.150114)
			(stroke
				(width 0.1)
				(type default)
			)
			(layer "B.Fab")
		)
		(fp_line
			(start -0.299974 0.150114)
			(end 0.299974 0.150114)
			(stroke
				(width 0.1)
				(type default)
			)
			(layer "B.Fab")
		)
		(pad "1" smd rect
			(at 0.2667 0 270)
			(size 0.3048 0.381)
			(layers "B.Cu" "B.Mask" "B.Paste")
			(net "P0V8_PEX0")
		)
		(pad "2" smd rect
			(at -0.2667 0 270)
			(size 0.3048 0.381)
			(layers "B.Cu" "B.Mask" "B.Paste")
			(net "GND")
		)
	)
	(footprint ""
		(layer "B.Cu")
		(at 408.424888 -297.79976 90)
		(property "Reference" "C1887"
			(at 0 0 90)
			(layer "B.SilkS")
			(hide yes)
			(effects
				(font
					(size 1.27 1.27)
				)
				(justify mirror)
			)
		)
		(property "Value" ""
			(at 0 0 90)
			(layer "B.Fab")
			(effects
				(font
					(size 1.27 1.27)
				)
				(justify mirror)
			)
		)
		(duplicate_pad_numbers_are_jumpers no)
		(fp_line
			(start 0.299974 -0.150114)
			(end -0.299974 -0.150114)
			(stroke
				(width 0.1)
				(type default)
			)
			(layer "B.Fab")
		)
		(fp_line
			(start -0.299974 -0.150114)
			(end -0.299974 0.150114)
			(stroke
				(width 0.1)
				(type default)
			)
			(layer "B.Fab")
		)
		(fp_line
			(start 0.299974 0.150114)
			(end 0.299974 -0.150114)
			(stroke
				(width 0.1)
				(type default)
			)
			(layer "B.Fab")
		)
		(fp_line
			(start -0.299974 0.150114)
			(end 0.299974 0.150114)
			(stroke
				(width 0.1)
				(type default)
			)
			(layer "B.Fab")
		)
		(pad "1" smd rect
			(at 0.2667 0 270)
			(size 0.3048 0.381)
			(layers "B.Cu" "B.Mask" "B.Paste")
			(net "P0V8_PEX3")
		)
		(pad "2" smd rect
			(at -0.2667 0 270)
			(size 0.3048 0.381)
			(layers "B.Cu" "B.Mask" "B.Paste")
			(net "GND")
		)
	)
	(footprint ""
		(layer "B.Cu")
		(at 220.981016 -279.898856 -90)
		(property "Reference" "C4293"
			(at 0 0 90)
			(layer "B.SilkS")
			(hide yes)
			(effects
				(font
					(size 1.27 1.27)
				)
				(justify mirror)
			)
		)
		(property "Value" ""
			(at 0 0 90)
			(layer "B.Fab")
			(effects
				(font
					(size 1.27 1.27)
				)
				(justify mirror)
			)
		)
		(duplicate_pad_numbers_are_jumpers no)
		(fp_line
			(start -0.299974 0.150114)
			(end 0.299974 0.150114)
			(stroke
				(width 0.1)
				(type default)
			)
			(layer "B.Fab")
		)
		(fp_line
			(start 0.299974 0.150114)
			(end 0.299974 -0.150114)
			(stroke
				(width 0.1)
				(type default)
			)
			(layer "B.Fab")
		)
		(fp_line
			(start -0.299974 -0.150114)
			(end -0.299974 0.150114)
			(stroke
				(width 0.1)
				(type default)
			)
			(layer "B.Fab")
		)
		(fp_line
			(start 0.299974 -0.150114)
			(end -0.299974 -0.150114)
			(stroke
				(width 0.1)
				(type default)
			)
			(layer "B.Fab")
		)
		(pad "1" smd rect
			(at 0.2667 0 90)
			(size 0.3048 0.381)
			(layers "B.Cu" "B.Mask" "B.Paste")
			(net "P1V25_PEX1")
		)
		(pad "2" smd rect
			(at -0.2667 0 90)
			(size 0.3048 0.381)
			(layers "B.Cu" "B.Mask" "B.Paste")
			(net "GND")
		)
	)
	(footprint ""
		(layer "B.Cu")
		(at 396.0749 -296.64152 -90)
		(property "Reference" "C3563"
			(at 0 0 90)
			(layer "B.SilkS")
			(hide yes)
			(effects
				(font
					(size 1.27 1.27)
				)
				(justify mirror)
			)
		)
		(property "Value" ""
			(at 0 0 90)
			(layer "B.Fab")
			(effects
				(font
					(size 1.27 1.27)
				)
				(justify mirror)
			)
		)
		(duplicate_pad_numbers_are_jumpers no)
		(fp_line
			(start -0.299974 0.150114)
			(end 0.299974 0.150114)
			(stroke
				(width 0.1)
				(type default)
			)
			(layer "B.Fab")
		)
		(fp_line
			(start 0.299974 0.150114)
			(end 0.299974 -0.150114)
			(stroke
				(width 0.1)
				(type default)
			)
			(layer "B.Fab")
		)
		(fp_line
			(start -0.299974 -0.150114)
			(end -0.299974 0.150114)
			(stroke
				(width 0.1)
				(type default)
			)
			(layer "B.Fab")
		)
		(fp_line
			(start 0.299974 -0.150114)
			(end -0.299974 -0.150114)
			(stroke
				(width 0.1)
				(type default)
			)
			(layer "B.Fab")
		)
		(pad "1" smd rect
			(at 0.2667 0 90)
			(size 0.3048 0.381)
			(layers "B.Cu" "B.Mask" "B.Paste")
			(net "PCEPLL3_VDDA18_PEX3")
		)
		(pad "2" smd rect
			(at -0.2667 0 90)
			(size 0.3048 0.381)
			(layers "B.Cu" "B.Mask" "B.Paste")
			(net "GND")
		)
	)
	(footprint ""
		(layer "B.Cu")
		(at 340.493858 -220.38691 90)
		(property "Reference" "C2072"
			(at 0 0 90)
			(layer "B.SilkS")
			(hide yes)
			(effects
				(font
					(size 1.27 1.27)
				)
				(justify mirror)
			)
		)
		(property "Value" ""
			(at 0 0 90)
			(layer "B.Fab")
			(effects
				(font
					(size 1.27 1.27)
				)
				(justify mirror)
			)
		)
		(duplicate_pad_numbers_are_jumpers no)
		(fp_line
			(start 0.69215 -0.2921)
			(end -0.69215 -0.2921)
			(stroke
				(width 0.1524)
				(type default)
			)
			(layer "B.SilkS")
		)
		(fp_line
			(start -0.69215 -0.2921)
			(end -0.69215 0.2921)
			(stroke
				(width 0.1524)
				(type default)
			)
			(layer "B.SilkS")
		)
		(fp_line
			(start 0.69215 0.2921)
			(end 0.69215 -0.2921)
			(stroke
				(width 0.1524)
				(type default)
			)
			(layer "B.SilkS")
		)
		(fp_line
			(start -0.69215 0.2921)
			(end 0.69215 0.2921)
			(stroke
				(width 0.1524)
				(type default)
			)
			(layer "B.SilkS")
		)
		(fp_line
			(start 0.51435 -0.2794)
			(end -0.51435 -0.2794)
			(stroke
				(width 0.1)
				(type default)
			)
			(layer "B.Fab")
		)
		(fp_line
			(start -0.51435 -0.2794)
			(end -0.51435 0.2794)
			(stroke
				(width 0.1)
				(type default)
			)
			(layer "B.Fab")
		)
		(fp_line
			(start 0.51435 0.2794)
			(end 0.51435 -0.2794)
			(stroke
				(width 0.1)
				(type default)
			)
			(layer "B.Fab")
		)
		(fp_line
			(start -0.51435 0.2794)
			(end 0.51435 0.2794)
			(stroke
				(width 0.1)
				(type default)
			)
			(layer "B.Fab")
		)
		(pad "1" smd circle
			(at 0.40005 0 270)
			(size 0 0)
			(layers "B.Cu" "B.Mask" "B.Paste")
			(net "P3V3_VCC_FPGA_CORE")
		)
		(pad "2" smd circle
			(at -0.40005 0 270)
			(size 0 0)
			(layers "B.Cu" "B.Mask" "B.Paste")
			(net "GND")
		)
		(zone
			(layer "B.Cu")
			(hatch none 0.5)
			(connect_pads
				(clearance 0)
			)
			(min_thickness 0.25)
			(keepout
				(tracks not_allowed)
				(vias allowed)
				(pads allowed)
				(copperpour not_allowed)
				(footprints allowed)
			)
			(placement
				(enabled no)
				(sheetname "")
			)
			(fill
				(thermal_gap 0.5)
				(thermal_bridge_width 0.5)
				(island_removal_mode 0)
			)
			(polygon
				(pts
					(xy 340.581488 -220.57741) (xy 340.639654 -220.48597) (xy 340.639654 -220.28658) (xy 340.581488 -220.19641)
					(xy 340.406228 -220.19641) (xy 340.347808 -220.28658) (xy 340.347808 -220.48597) (xy 340.405974 -220.57741)
				)
			)
		)
	)
	(footprint ""
		(layer "B.Cu")
		(at 294.69969 -299.699934 -90)
		(property "Reference" "C1719"
			(at 0 0 90)
			(layer "B.SilkS")
			(hide yes)
			(effects
				(font
					(size 1.27 1.27)
				)
				(justify mirror)
			)
		)
		(property "Value" ""
			(at 0 0 90)
			(layer "B.Fab")
			(effects
				(font
					(size 1.27 1.27)
				)
				(justify mirror)
			)
		)
		(duplicate_pad_numbers_are_jumpers no)
		(fp_line
			(start -0.299974 0.150114)
			(end 0.299974 0.150114)
			(stroke
				(width 0.1)
				(type default)
			)
			(layer "B.Fab")
		)
		(fp_line
			(start 0.299974 0.150114)
			(end 0.299974 -0.150114)
			(stroke
				(width 0.1)
				(type default)
			)
			(layer "B.Fab")
		)
		(fp_line
			(start -0.299974 -0.150114)
			(end -0.299974 0.150114)
			(stroke
				(width 0.1)
				(type default)
			)
			(layer "B.Fab")
		)
		(fp_line
			(start 0.299974 -0.150114)
			(end -0.299974 -0.150114)
			(stroke
				(width 0.1)
				(type default)
			)
			(layer "B.Fab")
		)
		(pad "1" smd rect
			(at 0.2667 0 90)
			(size 0.3048 0.381)
			(layers "B.Cu" "B.Mask" "B.Paste")
			(net "P0V8_SERDES_VDDA_PEX2")
		)
		(pad "2" smd rect
			(at -0.2667 0 90)
			(size 0.3048 0.381)
			(layers "B.Cu" "B.Mask" "B.Paste")
			(net "GND")
		)
	)
	(footprint ""
		(layer "B.Cu")
		(at 237.475776 -224.424494 -90)
		(property "Reference" "C4490"
			(at 0 0 90)
			(layer "B.SilkS")
			(hide yes)
			(effects
				(font
					(size 1.27 1.27)
				)
				(justify mirror)
			)
		)
		(property "Value" ""
			(at 0 0 90)
			(layer "B.Fab")
			(effects
				(font
					(size 1.27 1.27)
				)
				(justify mirror)
			)
		)
		(duplicate_pad_numbers_are_jumpers no)
		(fp_line
			(start -0.7874 0.4064)
			(end 0.7874 0.4064)
			(stroke
				(width 0.1524)
				(type default)
			)
			(layer "B.SilkS")
		)
		(fp_line
			(start 0.7874 0.4064)
			(end 0.7874 -0.4064)
			(stroke
				(width 0.1524)
				(type default)
			)
			(layer "B.SilkS")
		)
		(fp_line
			(start -0.7874 -0.4064)
			(end -0.7874 0.4064)
			(stroke
				(width 0.1524)
				(type default)
			)
			(layer "B.SilkS")
		)
		(fp_line
			(start 0.7874 -0.4064)
			(end -0.7874 -0.4064)
			(stroke
				(width 0.1524)
				(type default)
			)
			(layer "B.SilkS")
		)
		(fp_line
			(start -0.67945 0.3048)
			(end -0.120396 0.3048)
			(stroke
				(width 0.1)
				(type default)
			)
			(layer "B.Fab")
		)
		(fp_line
			(start -0.120396 0.3048)
			(end -0.120396 0.2794)
			(stroke
				(width 0.1)
				(type default)
			)
			(layer "B.Fab")
		)
		(fp_line
			(start 0.12065 0.3048)
			(end 0.67945 0.3048)
			(stroke
				(width 0.1)
				(type default)
			)
			(layer "B.Fab")
		)
		(fp_line
			(start 0.67945 0.3048)
			(end 0.67945 -0.305054)
			(stroke
				(width 0.1)
				(type default)
			)
			(layer "B.Fab")
		)
		(fp_line
			(start -0.120396 0.2794)
			(end 0.12065 0.2794)
			(stroke
				(width 0.1)
				(type default)
			)
			(layer "B.Fab")
		)
		(fp_line
			(start 0.12065 0.2794)
			(end 0.12065 0.3048)
			(stroke
				(width 0.1)
				(type default)
			)
			(layer "B.Fab")
		)
		(fp_line
			(start -0.12065 -0.2794)
			(end -0.12065 -0.3048)
			(stroke
				(width 0.1)
				(type default)
			)
			(layer "B.Fab")
		)
		(fp_line
			(start 0.12065 -0.2794)
			(end -0.12065 -0.2794)
			(stroke
				(width 0.1)
				(type default)
			)
			(layer "B.Fab")
		)
		(fp_line
			(start -0.67945 -0.3048)
			(end -0.67945 0.3048)
			(stroke
				(width 0.1)
				(type default)
			)
			(layer "B.Fab")
		)
		(fp_line
			(start -0.12065 -0.3048)
			(end -0.67945 -0.3048)
			(stroke
				(width 0.1)
				(type default)
			)
			(layer "B.Fab")
		)
		(fp_line
			(start 0.12065 -0.305054)
			(end 0.12065 -0.2794)
			(stroke
				(width 0.1)
				(type default)
			)
			(layer "B.Fab")
		)
		(fp_line
			(start 0.67945 -0.305054)
			(end 0.12065 -0.305054)
			(stroke
				(width 0.1)
				(type default)
			)
			(layer "B.Fab")
		)
		(pad "1" smd circle
			(at 0.40005 0 90)
			(size 0 0)
			(layers "B.Cu" "B.Mask" "B.Paste")
			(net "VR_TYPE_ADC_R")
		)
		(pad "2" smd circle
			(at -0.40005 0 90)
			(size 0 0)
			(layers "B.Cu" "B.Mask" "B.Paste")
			(net "GND")
		)
	)
	(footprint ""
		(layer "B.Cu")
		(at 223.533716 -196.989192 90)
		(property "Reference" "R464"
			(at 0 0 90)
			(layer "B.SilkS")
			(hide yes)
			(effects
				(font
					(size 1.27 1.27)
				)
				(justify mirror)
			)
		)
		(property "Value" ""
			(at 0 0 90)
			(layer "B.Fab")
			(effects
				(font
					(size 1.27 1.27)
				)
				(justify mirror)
			)
		)
		(duplicate_pad_numbers_are_jumpers no)
		(fp_line
			(start 0.7874 -0.4064)
			(end -0.7874 -0.4064)
			(stroke
				(width 0.1524)
				(type default)
			)
			(layer "B.SilkS")
		)
		(fp_line
			(start -0.7874 -0.4064)
			(end -0.7874 0.4064)
			(stroke
				(width 0.1524)
				(type default)
			)
			(layer "B.SilkS")
		)
		(fp_line
			(start 0.7874 0.4064)
			(end 0.7874 -0.4064)
			(stroke
				(width 0.1524)
				(type default)
			)
			(layer "B.SilkS")
		)
		(fp_line
			(start -0.7874 0.4064)
			(end 0.7874 0.4064)
			(stroke
				(width 0.1524)
				(type default)
			)
			(layer "B.SilkS")
		)
		(fp_line
			(start 0.67945 -0.305054)
			(end 0.12065 -0.305054)
			(stroke
				(width 0.1)
				(type default)
			)
			(layer "B.Fab")
		)
		(fp_line
			(start 0.12065 -0.305054)
			(end 0.12065 -0.2794)
			(stroke
				(width 0.1)
				(type default)
			)
			(layer "B.Fab")
		)
		(fp_line
			(start -0.12065 -0.3048)
			(end -0.67945 -0.3048)
			(stroke
				(width 0.1)
				(type default)
			)
			(layer "B.Fab")
		)
		(fp_line
			(start -0.67945 -0.3048)
			(end -0.67945 0.3048)
			(stroke
				(width 0.1)
				(type default)
			)
			(layer "B.Fab")
		)
		(fp_line
			(start 0.12065 -0.2794)
			(end -0.12065 -0.2794)
			(stroke
				(width 0.1)
				(type default)
			)
			(layer "B.Fab")
		)
		(fp_line
			(start -0.12065 -0.2794)
			(end -0.12065 -0.3048)
			(stroke
				(width 0.1)
				(type default)
			)
			(layer "B.Fab")
		)
		(fp_line
			(start 0.12065 0.2794)
			(end 0.12065 0.3048)
			(stroke
				(width 0.1)
				(type default)
			)
			(layer "B.Fab")
		)
		(fp_line
			(start -0.120396 0.2794)
			(end 0.12065 0.2794)
			(stroke
				(width 0.1)
				(type default)
			)
			(layer "B.Fab")
		)
		(fp_line
			(start 0.67945 0.3048)
			(end 0.67945 -0.305054)
			(stroke
				(width 0.1)
				(type default)
			)
			(layer "B.Fab")
		)
		(fp_line
			(start 0.12065 0.3048)
			(end 0.67945 0.3048)
			(stroke
				(width 0.1)
				(type default)
			)
			(layer "B.Fab")
		)
		(fp_line
			(start -0.120396 0.3048)
			(end -0.120396 0.2794)
			(stroke
				(width 0.1)
				(type default)
			)
			(layer "B.Fab")
		)
		(fp_line
			(start -0.67945 0.3048)
			(end -0.120396 0.3048)
			(stroke
				(width 0.1)
				(type default)
			)
			(layer "B.Fab")
		)
		(pad "1" smd circle
			(at 0.40005 0 270)
			(size 0 0)
			(layers "B.Cu" "B.Mask" "B.Paste")
			(net "SPI_BIC1_MISO_R")
		)
		(pad "2" smd circle
			(at -0.40005 0 270)
			(size 0 0)
			(layers "B.Cu" "B.Mask" "B.Paste")
			(net "SPI_BIC1_MISO_R1")
		)
	)
	(footprint ""
		(layer "B.Cu")
		(at 202.090274 -259.311648 90)
		(property "Reference" "R6337"
			(at 0 0 90)
			(layer "B.SilkS")
			(hide yes)
			(effects
				(font
					(size 1.27 1.27)
				)
				(justify mirror)
			)
		)
		(property "Value" ""
			(at 0 0 90)
			(layer "B.Fab")
			(effects
				(font
					(size 1.27 1.27)
				)
				(justify mirror)
			)
		)
		(duplicate_pad_numbers_are_jumpers no)
		(fp_line
			(start 0.7874 -0.4064)
			(end -0.7874 -0.4064)
			(stroke
				(width 0.1524)
				(type default)
			)
			(layer "B.SilkS")
		)
		(fp_line
			(start -0.7874 -0.4064)
			(end -0.7874 0.4064)
			(stroke
				(width 0.1524)
				(type default)
			)
			(layer "B.SilkS")
		)
		(fp_line
			(start 0.7874 0.4064)
			(end 0.7874 -0.4064)
			(stroke
				(width 0.1524)
				(type default)
			)
			(layer "B.SilkS")
		)
		(fp_line
			(start -0.7874 0.4064)
			(end 0.7874 0.4064)
			(stroke
				(width 0.1524)
				(type default)
			)
			(layer "B.SilkS")
		)
		(fp_line
			(start 0.67945 -0.305054)
			(end 0.12065 -0.305054)
			(stroke
				(width 0.1)
				(type default)
			)
			(layer "B.Fab")
		)
		(fp_line
			(start 0.12065 -0.305054)
			(end 0.12065 -0.2794)
			(stroke
				(width 0.1)
				(type default)
			)
			(layer "B.Fab")
		)
		(fp_line
			(start -0.12065 -0.3048)
			(end -0.67945 -0.3048)
			(stroke
				(width 0.1)
				(type default)
			)
			(layer "B.Fab")
		)
		(fp_line
			(start -0.67945 -0.3048)
			(end -0.67945 0.3048)
			(stroke
				(width 0.1)
				(type default)
			)
			(layer "B.Fab")
		)
		(fp_line
			(start 0.12065 -0.2794)
			(end -0.12065 -0.2794)
			(stroke
				(width 0.1)
				(type default)
			)
			(layer "B.Fab")
		)
		(fp_line
			(start -0.12065 -0.2794)
			(end -0.12065 -0.3048)
			(stroke
				(width 0.1)
				(type default)
			)
			(layer "B.Fab")
		)
		(fp_line
			(start 0.12065 0.2794)
			(end 0.12065 0.3048)
			(stroke
				(width 0.1)
				(type default)
			)
			(layer "B.Fab")
		)
		(fp_line
			(start -0.120396 0.2794)
			(end 0.12065 0.2794)
			(stroke
				(width 0.1)
				(type default)
			)
			(layer "B.Fab")
		)
		(fp_line
			(start 0.67945 0.3048)
			(end 0.67945 -0.305054)
			(stroke
				(width 0.1)
				(type default)
			)
			(layer "B.Fab")
		)
		(fp_line
			(start 0.12065 0.3048)
			(end 0.67945 0.3048)
			(stroke
				(width 0.1)
				(type default)
			)
			(layer "B.Fab")
		)
		(fp_line
			(start -0.120396 0.3048)
			(end -0.120396 0.2794)
			(stroke
				(width 0.1)
				(type default)
			)
			(layer "B.Fab")
		)
		(fp_line
			(start -0.67945 0.3048)
			(end -0.120396 0.3048)
			(stroke
				(width 0.1)
				(type default)
			)
			(layer "B.Fab")
		)
		(pad "1" smd circle
			(at 0.40005 0 270)
			(size 0 0)
			(layers "B.Cu" "B.Mask" "B.Paste")
			(net "P1V8_PEX")
		)
		(pad "2" smd circle
			(at -0.40005 0 270)
			(size 0 0)
			(layers "B.Cu" "B.Mask" "B.Paste")
			(net "PEX_MUX_A1")
		)
	)
)
